# T6G (Grand Teton) — schematic netlist excerpt (pin names and nets, part order shuffled) for the footprints in the layout excerpt that follows; sources: Cadence DE-HDL packaged netlist, KiCad conversion of 04192023_DAF0TMB3IC0_F0TG_MB_C_brd_V02_OCP.brd

C2145  Q_CAP  22UF 4V 20% X6S  pkg C0402  page 68 : A = PVDDIO_P0 ; B = GND
R6134  Q_RES  1K 1% CHIP  pkg 0402LF  page 84 : A = FAB_REV_ID1 ; B = GND

(kicad_pcb
	(version 20260206)
	(generator "pcbnew")
	(generator_version "10.0")
	(general
		(thickness 1.6)
		(legacy_teardrops no)
	)
	(paper "A4")
	(title_block
		(title "04192023_DAF0TMB3IC0_F0TG_MB_C_brd_V02_OCP.brd")
		(comment 1 "Grand Teton / footprints 6049-6050 of 8354")
	)
	(layers
		(0 "F.Cu" signal "TOP")
		(4 "In1.Cu" signal "GND")
		(6 "In2.Cu" signal "IN1")
		(8 "In3.Cu" signal "GND1")
		(10 "In4.Cu" signal "IN2")
		(12 "In5.Cu" signal "GND2")
		(14 "In6.Cu" signal "IN3")
		(16 "In7.Cu" signal "GND3")
		(18 "In8.Cu" signal "VCC")
		(20 "In9.Cu" signal "VCC1")
		(22 "In10.Cu" signal "GND4")
		(24 "In11.Cu" signal "IN4")
		(26 "In12.Cu" signal "GND5")
		(28 "In13.Cu" signal "IN5")
		(30 "In14.Cu" signal "GND6")
		(32 "In15.Cu" signal "IN6")
		(34 "In16.Cu" signal "GND7")
		(2 "B.Cu" signal "BOTTOM")
		(9 "F.Adhes" user "F.Adhesive")
		(11 "B.Adhes" user "B.Adhesive")
		(13 "F.Paste" user "Package Geometry/Pastemask Top")
		(15 "B.Paste" user "Package Geometry/Pastemask Bottom")
		(5 "F.SilkS" user "Ref Des/Silkscreen Top")
		(7 "B.SilkS" user "Ref Des/Silkscreen Bottom")
		(1 "F.Mask" user "Board Geometry/Soldermask Top")
		(3 "B.Mask" user "Board Geometry/Soldermask Bottom")
		(17 "Dwgs.User" user "User.Drawings")
		(19 "Cmts.User" user "User.Comments")
		(21 "Eco1.User" user "User.Eco1")
		(23 "Eco2.User" user "User.Eco2")
		(25 "Edge.Cuts" user "Board Geometry/Outline")
		(27 "Margin" user)
		(31 "F.CrtYd" user "Package Geometry/Place Bound Top")
		(29 "B.CrtYd" user "Package Geometry/Place Bound Bottom")
		(35 "F.Fab" user "Ref Des/Assembly Top")
		(33 "B.Fab" user "Ref Des/Assembly Bottom")
	)
	(footprint ""
		(layer "B.Cu")
		(at 353.900232 -261.255002 180)
		(property "Reference" "C2145"
			(at 0 0 0)
			(layer "B.SilkS")
			(hide yes)
			(effects
				(font
					(size 1.27 1.27)
				)
				(justify mirror)
			)
		)
		(property "Value" ""
			(at 0 0 0)
			(layer "B.Fab")
			(effects
				(font
					(size 1.27 1.27)
				)
				(justify mirror)
			)
		)
		(duplicate_pad_numbers_are_jumpers no)
		(fp_line
			(start 0.7874 0.4064)
			(end 0.7874 -0.4064)
			(stroke
				(width 0.1524)
				(type default)
			)
			(layer "B.SilkS")
		)
		(fp_line
			(start 0.7874 -0.4064)
			(end -0.7874 -0.4064)
			(stroke
				(width 0.1524)
				(type default)
			)
			(layer "B.SilkS")
		)
		(fp_line
			(start -0.7874 0.4064)
			(end 0.7874 0.4064)
			(stroke
				(width 0.1524)
				(type default)
			)
			(layer "B.SilkS")
		)
		(fp_line
			(start -0.7874 -0.4064)
			(end -0.7874 0.4064)
			(stroke
				(width 0.1524)
				(type default)
			)
			(layer "B.SilkS")
		)
		(fp_line
			(start 0.67945 0.3048)
			(end 0.67945 -0.305054)
			(stroke
				(width 0.1)
				(type default)
			)
			(layer "B.Fab")
		)
		(fp_line
			(start 0.67945 -0.305054)
			(end 0.12065 -0.305054)
			(stroke
				(width 0.1)
				(type default)
			)
			(layer "B.Fab")
		)
		(fp_line
			(start 0.12065 0.3048)
			(end 0.67945 0.3048)
			(stroke
				(width 0.1)
				(type default)
			)
			(layer "B.Fab")
		)
		(fp_line
			(start 0.12065 0.2794)
			(end 0.12065 0.3048)
			(stroke
				(width 0.1)
				(type default)
			)
			(layer "B.Fab")
		)
		(fp_line
			(start 0.12065 -0.2794)
			(end -0.12065 -0.2794)
			(stroke
				(width 0.1)
				(type default)
			)
			(layer "B.Fab")
		)
		(fp_line
			(start 0.12065 -0.305054)
			(end 0.12065 -0.2794)
			(stroke
				(width 0.1)
				(type default)
			)
			(layer "B.Fab")
		)
		(fp_line
			(start -0.120396 0.3048)
			(end -0.120396 0.2794)
			(stroke
				(width 0.1)
				(type default)
			)
			(layer "B.Fab")
		)
		(fp_line
			(start -0.120396 0.2794)
			(end 0.12065 0.2794)
			(stroke
				(width 0.1)
				(type default)
			)
			(layer "B.Fab")
		)
		(fp_line
			(start -0.12065 -0.2794)
			(end -0.12065 -0.3048)
			(stroke
				(width 0.1)
				(type default)
			)
			(layer "B.Fab")
		)
		(fp_line
			(start -0.12065 -0.3048)
			(end -0.67945 -0.3048)
			(stroke
				(width 0.1)
				(type default)
			)
			(layer "B.Fab")
		)
		(fp_line
			(start -0.67945 0.3048)
			(end -0.120396 0.3048)
			(stroke
				(width 0.1)
				(type default)
			)
			(layer "B.Fab")
		)
		(fp_line
			(start -0.67945 -0.3048)
			(end -0.67945 0.3048)
			(stroke
				(width 0.1)
				(type default)
			)
			(layer "B.Fab")
		)
		(pad "1" smd circle
			(at 0.40005 0)
			(size 0 0)
			(layers "B.Cu" "B.Mask" "B.Paste")
			(net "PVDDIO_P0")
		)
		(pad "2" smd circle
			(at -0.40005 0)
			(size 0 0)
			(layers "B.Cu" "B.Mask" "B.Paste")
			(net "GND")
		)
	)
	(footprint ""
		(layer "B.Cu")
		(at 396.142972 -200.754996 90)
		(property "Reference" "R6134"
			(at 0 0 90)
			(layer "B.SilkS")
			(hide yes)
			(effects
				(font
					(size 1.27 1.27)
				)
				(justify mirror)
			)
		)
		(property "Value" ""
			(at 0 0 90)
			(layer "B.Fab")
			(effects
				(font
					(size 1.27 1.27)
				)
				(justify mirror)
			)
		)
		(duplicate_pad_numbers_are_jumpers no)
		(fp_line
			(start 0.7874 -0.4064)
			(end -0.7874 -0.4064)
			(stroke
				(width 0.1524)
				(type default)
			)
			(layer "B.SilkS")
		)
		(fp_line
			(start -0.7874 -0.4064)
			(end -0.7874 0.4064)
			(stroke
				(width 0.1524)
				(type default)
			)
			(layer "B.SilkS")
		)
		(fp_line
			(start 0.7874 0.4064)
			(end 0.7874 -0.4064)
			(stroke
				(width 0.1524)
				(type default)
			)
			(layer "B.SilkS")
		)
		(fp_line
			(start -0.7874 0.4064)
			(end 0.7874 0.4064)
			(stroke
				(width 0.1524)
				(type default)
			)
			(layer "B.SilkS")
		)
		(fp_line
			(start 0.67945 -0.305054)
			(end 0.12065 -0.305054)
			(stroke
				(width 0.1)
				(type default)
			)
			(layer "B.Fab")
		)
		(fp_line
			(start 0.12065 -0.305054)
			(end 0.12065 -0.2794)
			(stroke
				(width 0.1)
				(type default)
			)
			(layer "B.Fab")
		)
		(fp_line
			(start -0.12065 -0.3048)
			(end -0.67945 -0.3048)
			(stroke
				(width 0.1)
				(type default)
			)
			(layer "B.Fab")
		)
		(fp_line
			(start -0.67945 -0.3048)
			(end -0.67945 0.3048)
			(stroke
				(width 0.1)
				(type default)
			)
			(layer "B.Fab")
		)
		(fp_line
			(start 0.12065 -0.2794)
			(end -0.12065 -0.2794)
			(stroke
				(width 0.1)
				(type default)
			)
			(layer "B.Fab")
		)
		(fp_line
			(start -0.12065 -0.2794)
			(end -0.12065 -0.3048)
			(stroke
				(width 0.1)
				(type default)
			)
			(layer "B.Fab")
		)
		(fp_line
			(start 0.12065 0.2794)
			(end 0.12065 0.3048)
			(stroke
				(width 0.1)
				(type default)
			)
			(layer "B.Fab")
		)
		(fp_line
			(start -0.120396 0.2794)
			(end 0.12065 0.2794)
			(stroke
				(width 0.1)
				(type default)
			)
			(layer "B.Fab")
		)
		(fp_line
			(start 0.67945 0.3048)
			(end 0.67945 -0.305054)
			(stroke
				(width 0.1)
				(type default)
			)
			(layer "B.Fab")
		)
		(fp_line
			(start 0.12065 0.3048)
			(end 0.67945 0.3048)
			(stroke
				(width 0.1)
				(type default)
			)
			(layer "B.Fab")
		)
		(fp_line
			(start -0.120396 0.3048)
			(end -0.120396 0.2794)
			(stroke
				(width 0.1)
				(type default)
			)
			(layer "B.Fab")
		)
		(fp_line
			(start -0.67945 0.3048)
			(end -0.120396 0.3048)
			(stroke
				(width 0.1)
				(type default)
			)
			(layer "B.Fab")
		)
		(pad "1" smd circle
			(at 0.40005 0 270)
			(size 0 0)
			(layers "B.Cu" "B.Mask" "B.Paste")
			(net "FAB_REV_ID1")
		)
		(pad "2" smd circle
			(at -0.40005 0 270)
			(size 0 0)
			(layers "B.Cu" "B.Mask" "B.Paste")
			(net "GND")
		)
	)
)
